FILE_TYPE = MACRO_DRAWING;
SET COLOR_WIRE YELLOW;
SET COLOR_PROP ORANGE;
SET COLOR_DOT WHITE;
SET COLOR_ARC YELLOW;
SET COLOR_BODY GREEN;
SET COLOR_NOTE PURPLE;
SET PROP_DISPLAY VALUE;
SET PAGE_NUMBER P46;
FORCEADD OFFPAGE..3
R 2
(-6325 8050);
FORCEPROP 2 LAST $XR0 236 
J 0
(-6635 8050);
DISPLAY 0.638298 (-6635 8050);
PAINT MONO (-6635 8050);
FORCEPROP 2 LAST CDS_LIB standard
J 0
(-6325 8050);
PAINT MONO (-6325 8050);
DISPLAY INVISIBLE (-6325 8050);
FORCEPROP 1 LAST OFFPAGE TRUE
J 2
(-6650 7925);
DISPLAY 0.872340 (-6650 7925);
DISPLAY INVISIBLE (-6650 7925);
FORCEPROP 1 LAST COMMENT_BODY TRUE
J 2
(-6275 7950);
DISPLAY 0.872340 (-6275 7950);
PAINT GREEN (-6275 7950);
DISPLAY INVISIBLE (-6275 7950);
FORCEPROP 2 LAST PATH I1
J 0
(-6275 8125);
DISPLAY 1.021277 (-6275 8125);
DISPLAY INVISIBLE (-6275 8125);
FORCEADD OFFPAGE..2
(-475 9500);
FORCEPROP 2 LAST $XR0 120 
J 0
(-286 9500);
DISPLAY 0.638298 (-286 9500);
PAINT MONO (-286 9500);
FORCEPROP 2 LAST CDS_LIB standard
J 0
(-475 9500);
PAINT MONO (-475 9500);
DISPLAY INVISIBLE (-475 9500);
FORCEPROP 1 LAST OFFPAGE TRUE
J 0
(-150 9375);
DISPLAY 1.170213 (-150 9375);
PAINT GREEN (-150 9375);
DISPLAY INVISIBLE (-150 9375);
FORCEPROP 1 LAST COMMENT_BODY TRUE
J 0
(-520 9405);
DISPLAY 1.170213 (-520 9405);
PAINT GREEN (-520 9405);
DISPLAY INVISIBLE (-520 9405);
FORCEPROP 2 LAST PATH I10
J 0
(-300 9575);
DISPLAY 1.021277 (-300 9575);
DISPLAY INVISIBLE (-300 9575);
FORCEADD OFFPAGE..2
(-475 9550);
FORCEPROP 2 LAST $XR0 120 
J 0
(-286 9550);
DISPLAY 0.638298 (-286 9550);
PAINT MONO (-286 9550);
FORCEPROP 2 LAST CDS_LIB standard
J 0
(-475 9550);
PAINT MONO (-475 9550);
DISPLAY INVISIBLE (-475 9550);
FORCEPROP 1 LAST OFFPAGE TRUE
J 0
(-150 9425);
DISPLAY 1.170213 (-150 9425);
PAINT GREEN (-150 9425);
DISPLAY INVISIBLE (-150 9425);
FORCEPROP 1 LAST COMMENT_BODY TRUE
J 0
(-520 9455);
DISPLAY 1.170213 (-520 9455);
PAINT GREEN (-520 9455);
DISPLAY INVISIBLE (-520 9455);
FORCEPROP 2 LAST PATH I11
J 0
(-300 9625);
DISPLAY 1.021277 (-300 9625);
DISPLAY INVISIBLE (-300 9625);
FORCEADD OFFPAGE..2
(-475 9600);
FORCEPROP 2 LAST $XR0 120 
J 0
(-286 9600);
DISPLAY 0.638298 (-286 9600);
PAINT MONO (-286 9600);
FORCEPROP 2 LAST CDS_LIB standard
J 0
(-475 9600);
PAINT MONO (-475 9600);
DISPLAY INVISIBLE (-475 9600);
FORCEPROP 1 LAST OFFPAGE TRUE
J 0
(-150 9475);
DISPLAY 1.170213 (-150 9475);
PAINT GREEN (-150 9475);
DISPLAY INVISIBLE (-150 9475);
FORCEPROP 1 LAST COMMENT_BODY TRUE
J 0
(-520 9505);
DISPLAY 1.170213 (-520 9505);
PAINT GREEN (-520 9505);
DISPLAY INVISIBLE (-520 9505);
FORCEPROP 2 LAST PATH I12
J 0
(-300 9675);
DISPLAY 1.021277 (-300 9675);
DISPLAY INVISIBLE (-300 9675);
FORCEADD OFFPAGE..2
(-475 9650);
FORCEPROP 2 LAST $XR0 120 
J 0
(-286 9650);
DISPLAY 0.638298 (-286 9650);
PAINT MONO (-286 9650);
FORCEPROP 2 LAST CDS_LIB standard
J 0
(-475 9650);
PAINT MONO (-475 9650);
DISPLAY INVISIBLE (-475 9650);
FORCEPROP 1 LAST OFFPAGE TRUE
J 0
(-150 9525);
DISPLAY 1.170213 (-150 9525);
PAINT GREEN (-150 9525);
DISPLAY INVISIBLE (-150 9525);
FORCEPROP 1 LAST COMMENT_BODY TRUE
J 0
(-520 9555);
DISPLAY 1.170213 (-520 9555);
PAINT GREEN (-520 9555);
DISPLAY INVISIBLE (-520 9555);
FORCEPROP 2 LAST PATH I13
J 0
(-300 9725);
DISPLAY 1.021277 (-300 9725);
DISPLAY INVISIBLE (-300 9725);
FORCEADD OFFPAGE..2
(-475 9700);
FORCEPROP 2 LAST $XR0 120 
J 0
(-286 9700);
DISPLAY 0.638298 (-286 9700);
PAINT MONO (-286 9700);
FORCEPROP 2 LAST CDS_LIB standard
J 0
(-475 9700);
PAINT MONO (-475 9700);
DISPLAY INVISIBLE (-475 9700);
FORCEPROP 1 LAST OFFPAGE TRUE
J 0
(-150 9575);
DISPLAY 1.170213 (-150 9575);
PAINT GREEN (-150 9575);
DISPLAY INVISIBLE (-150 9575);
FORCEPROP 1 LAST COMMENT_BODY TRUE
J 0
(-520 9605);
DISPLAY 1.170213 (-520 9605);
PAINT GREEN (-520 9605);
DISPLAY INVISIBLE (-520 9605);
FORCEPROP 2 LAST PATH I14
J 0
(-300 9775);
DISPLAY 1.021277 (-300 9775);
DISPLAY INVISIBLE (-300 9775);
FORCEADD OFFPAGE..4
(-475 8600);
FORCEPROP 2 LAST $XR0 80 
J 0
(-289 8600);
DISPLAY 0.638298 (-289 8600);
PAINT MONO (-289 8600);
FORCEPROP 2 LAST CDS_LIB standard
J 0
(-475 8600);
PAINT MONO (-475 8600);
DISPLAY INVISIBLE (-475 8600);
FORCEPROP 1 LAST OFFPAGE TRUE
J 0
(-150 8475);
DISPLAY 1.170213 (-150 8475);
PAINT GREEN (-150 8475);
DISPLAY INVISIBLE (-150 8475);
FORCEPROP 1 LAST COMMENT_BODY TRUE
J 0
(-500 8500);
DISPLAY 1.170213 (-500 8500);
PAINT GREEN (-500 8500);
DISPLAY INVISIBLE (-500 8500);
FORCEPROP 2 LAST PATH I15
J 0
(-275 8650);
DISPLAY 1.021277 (-275 8650);
DISPLAY INVISIBLE (-275 8650);
FORCEADD OFFPAGE..4
(-475 8650);
FORCEPROP 2 LAST $XR0 80 
J 0
(-289 8650);
DISPLAY 0.638298 (-289 8650);
PAINT MONO (-289 8650);
FORCEPROP 2 LAST CDS_LIB standard
J 0
(-475 8650);
PAINT MONO (-475 8650);
DISPLAY INVISIBLE (-475 8650);
FORCEPROP 1 LAST OFFPAGE TRUE
J 0
(-150 8525);
DISPLAY 1.170213 (-150 8525);
PAINT GREEN (-150 8525);
DISPLAY INVISIBLE (-150 8525);
FORCEPROP 1 LAST COMMENT_BODY TRUE
J 0
(-500 8550);
DISPLAY 1.170213 (-500 8550);
PAINT GREEN (-500 8550);
DISPLAY INVISIBLE (-500 8550);
FORCEPROP 2 LAST PATH I16
J 0
(-275 8700);
DISPLAY 1.021277 (-275 8700);
DISPLAY INVISIBLE (-275 8700);
FORCEADD OFFPAGE..2
(-475 8700);
FORCEPROP 2 LAST $XR1 213 
J 0
(-196 8700);
DISPLAY 0.638298 (-196 8700);
PAINT MONO (-196 8700);
FORCEPROP 2 LAST $XR0 80 
J 0
(-286 8700);
DISPLAY 0.638298 (-286 8700);
PAINT MONO (-286 8700);
FORCEPROP 2 LAST CDS_LIB standard
J 0
(-475 8700);
PAINT MONO (-475 8700);
DISPLAY INVISIBLE (-475 8700);
FORCEPROP 1 LAST OFFPAGE TRUE
J 0
(-150 8575);
DISPLAY 1.170213 (-150 8575);
PAINT GREEN (-150 8575);
DISPLAY INVISIBLE (-150 8575);
FORCEPROP 1 LAST COMMENT_BODY TRUE
J 0
(-520 8605);
DISPLAY 1.170213 (-520 8605);
PAINT GREEN (-520 8605);
DISPLAY INVISIBLE (-520 8605);
FORCEPROP 2 LAST PATH I17
J 0
(-275 8750);
DISPLAY 1.021277 (-275 8750);
DISPLAY INVISIBLE (-275 8750);
FORCEADD OFFPAGE..4
(-475 8550);
FORCEPROP 2 LAST $XR0 80 
J 0
(-289 8550);
DISPLAY 0.638298 (-289 8550);
PAINT MONO (-289 8550);
FORCEPROP 2 LAST CDS_LIB standard
J 0
(-475 8550);
PAINT MONO (-475 8550);
DISPLAY INVISIBLE (-475 8550);
FORCEPROP 1 LAST OFFPAGE TRUE
J 0
(-150 8425);
DISPLAY 1.170213 (-150 8425);
PAINT GREEN (-150 8425);
DISPLAY INVISIBLE (-150 8425);
FORCEPROP 1 LAST COMMENT_BODY TRUE
J 0
(-500 8450);
DISPLAY 1.170213 (-500 8450);
PAINT GREEN (-500 8450);
DISPLAY INVISIBLE (-500 8450);
FORCEPROP 2 LAST PATH I18
J 0
(-275 8600);
DISPLAY 1.021277 (-275 8600);
DISPLAY INVISIBLE (-275 8600);
FORCEADD OFFPAGE..2
R 2
(-6325 8100);
FORCEPROP 2 LAST $XR0 236 
J 0
(-6610 8100);
DISPLAY 0.638298 (-6610 8100);
PAINT MONO (-6610 8100);
FORCEPROP 2 LAST CDS_LIB standard
J 0
(-6325 8100);
PAINT MONO (-6325 8100);
DISPLAY INVISIBLE (-6325 8100);
FORCEPROP 1 LAST OFFPAGE TRUE
J 2
(-6650 7975);
DISPLAY 0.872340 (-6650 7975);
DISPLAY INVISIBLE (-6650 7975);
FORCEPROP 1 LAST COMMENT_BODY TRUE
J 2
(-6280 8005);
DISPLAY 0.872340 (-6280 8005);
PAINT GREEN (-6280 8005);
DISPLAY INVISIBLE (-6280 8005);
FORCEPROP 2 LAST PATH I2
J 0
(-6275 8175);
DISPLAY 1.021277 (-6275 8175);
DISPLAY INVISIBLE (-6275 8175);
FORCEADD OFFPAGE..1
(-6325 10000);
FORCEPROP 2 LAST $XR0 43 
J 0
(-6546 10000);
DISPLAY 0.638298 (-6546 10000);
PAINT MONO (-6546 10000);
FORCEPROP 2 LAST CDS_LIB standard
J 0
(-6325 10000);
PAINT MONO (-6325 10000);
DISPLAY INVISIBLE (-6325 10000);
FORCEPROP 1 LAST OFFPAGE TRUE
J 0
(-6000 9875);
DISPLAY 0.872340 (-6000 9875);
DISPLAY INVISIBLE (-6000 9875);
FORCEPROP 1 LAST COMMENT_BODY TRUE
J 0
(-6200 9900);
DISPLAY 0.872340 (-6200 9900);
PAINT GREEN (-6200 9900);
DISPLAY INVISIBLE (-6200 9900);
FORCEPROP 2 LAST PATH I26
J 0
(-6600 10050);
DISPLAY 1.021277 (-6600 10050);
DISPLAY INVISIBLE (-6600 10050);
FORCEADD OFFPAGE..4
(-475 10450);
FORCEPROP 2 LAST $XR0 120 
J 0
(-289 10450);
DISPLAY 0.638298 (-289 10450);
PAINT MONO (-289 10450);
FORCEPROP 2 LAST CDS_LIB standard
J 0
(-475 10450);
PAINT MONO (-475 10450);
DISPLAY INVISIBLE (-475 10450);
FORCEPROP 1 LAST OFFPAGE TRUE
J 0
(-150 10325);
DISPLAY 1.170213 (-150 10325);
PAINT GREEN (-150 10325);
DISPLAY INVISIBLE (-150 10325);
FORCEPROP 1 LAST COMMENT_BODY TRUE
J 0
(-500 10350);
DISPLAY 1.170213 (-500 10350);
PAINT GREEN (-500 10350);
DISPLAY INVISIBLE (-500 10350);
FORCEPROP 2 LAST PATH I37
J 0
(-275 10500);
DISPLAY 1.021277 (-275 10500);
DISPLAY INVISIBLE (-275 10500);
FORCEADD OFFPAGE..1
(-6325 10450);
FORCEPROP 2 LAST $XR0 43 
J 0
(-6546 10450);
DISPLAY 0.638298 (-6546 10450);
PAINT MONO (-6546 10450);
FORCEPROP 2 LAST CDS_LIB standard
J 0
(-6325 10450);
PAINT MONO (-6325 10450);
DISPLAY INVISIBLE (-6325 10450);
FORCEPROP 1 LAST OFFPAGE TRUE
J 0
(-6000 10325);
DISPLAY 0.872340 (-6000 10325);
DISPLAY INVISIBLE (-6000 10325);
FORCEPROP 1 LAST COMMENT_BODY TRUE
J 0
(-6200 10350);
DISPLAY 0.872340 (-6200 10350);
PAINT GREEN (-6200 10350);
DISPLAY INVISIBLE (-6200 10350);
FORCEPROP 2 LAST PATH I4
J 0
(-6275 10525);
DISPLAY 1.021277 (-6275 10525);
DISPLAY INVISIBLE (-6275 10525);
FORCEADD SOCKET4677_AZIF0045P001C01CS..3
(-3400 9125);
FORCEPROP 1 LAST PART_NUMBER DGA^7000023
J 0
(-4450 10725);
DISPLAY 0.723404 (-4450 10725);
PAINT GREEN (-4450 10725);
DISPLAY INVISIBLE (-4450 10725);
FORCEPROP 2 LAST PART_TYPE SMLF
J 0
(-4450 10900);
DISPLAY 1.021277 (-4450 10900);
FORCEPROP 1 LAST MATERIAL IO
J 0
(-4450 10650);
DISPLAY 0.723404 (-4450 10650);
PAINT GREEN (-4450 10650);
FORCEPROP 2 LAST VALUE SOCKET4677_AZIF0045-P001C01CS
J 0
(-4450 10850);
DISPLAY 1.021277 (-4450 10850);
FORCEPROP 1 LAST $LOCATION U1
J 0
(-4450 10800);
DISPLAY 0.723404 (-4450 10800);
PAINT GREEN (-4450 10800);
FORCEPROP 0 LASTPIN (-4600 10450) $PN CV20
J 2
(-4610 10460);
DISPLAY 0.680851 (-4610 10460);
PAINT MONO (-4610 10460);
FORCEPROP 0 LASTPIN (-4600 8100) $PN CE64
J 2
(-4610 8110);
DISPLAY 0.680851 (-4610 8110);
PAINT MONO (-4610 8110);
FORCEPROP 0 LASTPIN (-4600 8050) $PN CD63
J 2
(-4610 8060);
DISPLAY 0.680851 (-4610 8060);
PAINT MONO (-4610 8060);
FORCEPROP 0 LASTPIN (-2200 8700) $PN CY20
J 0
(-2190 8710);
DISPLAY 0.680851 (-2190 8710);
PAINT MONO (-2190 8710);
FORCEPROP 0 LASTPIN (-2200 9700) $PN BA70
J 0
(-2190 9710);
DISPLAY 0.680851 (-2190 9710);
PAINT MONO (-2190 9710);
FORCEPROP 0 LASTPIN (-2200 9650) $PN AV71
J 0
(-2190 9660);
DISPLAY 0.680851 (-2190 9660);
PAINT MONO (-2190 9660);
FORCEPROP 0 LASTPIN (-4600 9500) $PN AU62
J 2
(-4610 9510);
DISPLAY 0.680851 (-4610 9510);
PAINT MONO (-4610 9510);
FORCEPROP 0 LASTPIN (-4600 8350) $PN AU64
J 2
(-4610 8360);
DISPLAY 0.680851 (-4610 8360);
PAINT MONO (-4610 8360);
FORCEPROP 0 LASTPIN (-4600 9050) $PN AV63
J 2
(-4610 9060);
DISPLAY 0.680851 (-4610 9060);
PAINT MONO (-4610 9060);
FORCEPROP 0 LASTPIN (-2200 10350) $PN AW19
J 0
(-2190 10360);
DISPLAY 0.680851 (-2190 10360);
PAINT MONO (-2190 10360);
FORCEPROP 0 LASTPIN (-4600 8950) $PN AW64
J 2
(-4610 8960);
DISPLAY 0.680851 (-4610 8960);
PAINT MONO (-4610 8960);
FORCEPROP 0 LASTPIN (-2200 9500) $PN AW70
J 0
(-2190 9510);
DISPLAY 0.680851 (-2190 9510);
PAINT MONO (-2190 9510);
FORCEPROP 0 LASTPIN (-4600 9350) $PN AY61
J 2
(-4610 9360);
DISPLAY 0.680851 (-4610 9360);
PAINT MONO (-4610 9360);
FORCEPROP 0 LASTPIN (-4600 9450) $PN AY67
J 2
(-4610 9460);
DISPLAY 0.680851 (-4610 9460);
PAINT MONO (-4610 9460);
FORCEPROP 0 LASTPIN (-4600 9000) $PN BA62
J 2
(-4610 9010);
DISPLAY 0.680851 (-4610 9010);
PAINT MONO (-4610 9010);
FORCEPROP 0 LASTPIN (-4600 9400) $PN BA66
J 2
(-4610 9410);
DISPLAY 0.680851 (-4610 9410);
PAINT MONO (-4610 9410);
FORCEPROP 0 LASTPIN (-4600 9200) $PN BA68
J 2
(-4610 9210);
DISPLAY 0.680851 (-4610 9210);
PAINT MONO (-4610 9210);
FORCEPROP 0 LASTPIN (-4600 9100) $PN BB61
J 2
(-4610 9110);
DISPLAY 0.680851 (-4610 9110);
PAINT MONO (-4610 9110);
FORCEPROP 0 LASTPIN (-4600 9550) $PN BB67
J 2
(-4610 9560);
DISPLAY 0.680851 (-4610 9560);
PAINT MONO (-4610 9560);
FORCEPROP 0 LASTPIN (-2200 8800) $PN BC25
J 0
(-2190 8810);
DISPLAY 0.680851 (-2190 8810);
PAINT MONO (-2190 8810);
FORCEPROP 0 LASTPIN (-4600 9150) $PN BC64
J 2
(-4610 9160);
DISPLAY 0.680851 (-4610 9160);
PAINT MONO (-4610 9160);
FORCEPROP 0 LASTPIN (-4600 8850) $PN BD61
J 2
(-4610 8860);
DISPLAY 0.680851 (-4610 8860);
PAINT MONO (-4610 8860);
FORCEPROP 0 LASTPIN (-4600 8200) $PN BD63
J 2
(-4610 8210);
DISPLAY 0.680851 (-4610 8210);
PAINT MONO (-4610 8210);
FORCEPROP 0 LASTPIN (-4600 8900) $PN BD65
J 2
(-4610 8910);
DISPLAY 0.680851 (-4610 8910);
PAINT MONO (-4610 8910);
FORCEPROP 0 LASTPIN (-2200 8850) $PN BE25
J 0
(-2190 8860);
DISPLAY 0.680851 (-2190 8860);
PAINT MONO (-2190 8860);
FORCEPROP 0 LASTPIN (-4600 8250) $PN BE62
J 2
(-4610 8260);
DISPLAY 0.680851 (-4610 8260);
PAINT MONO (-4610 8260);
FORCEPROP 0 LASTPIN (-4600 8550) $PN BF65
J 2
(-4610 8560);
DISPLAY 0.680851 (-4610 8560);
PAINT MONO (-4610 8560);
FORCEPROP 0 LASTPIN (-4600 8600) $PN BG62
J 2
(-4610 8610);
DISPLAY 0.680851 (-4610 8610);
PAINT MONO (-4610 8610);
FORCEPROP 0 LASTPIN (-4600 8700) $PN BG64
J 2
(-4610 8710);
DISPLAY 0.680851 (-4610 8710);
PAINT MONO (-4610 8710);
FORCEPROP 0 LASTPIN (-4600 8650) $PN BH63
J 2
(-4610 8660);
DISPLAY 0.680851 (-4610 8660);
PAINT MONO (-4610 8660);
FORCEPROP 0 LASTPIN (-4600 8500) $PN BH65
J 2
(-4610 8510);
DISPLAY 0.680851 (-4610 8510);
PAINT MONO (-4610 8510);
FORCEPROP 0 LASTPIN (-4600 8400) $PN BJ64
J 2
(-4610 8410);
DISPLAY 0.680851 (-4610 8410);
PAINT MONO (-4610 8410);
FORCEPROP 0 LASTPIN (-4600 8450) $PN BK63
J 2
(-4610 8460);
DISPLAY 0.680851 (-4610 8460);
PAINT MONO (-4610 8460);
FORCEPROP 0 LASTPIN (-4600 8300) $PN BM63
J 2
(-4610 8310);
DISPLAY 0.680851 (-4610 8310);
PAINT MONO (-4610 8310);
FORCEPROP 0 LASTPIN (-2200 9200) $PN CD65
J 0
(-2190 9210);
DISPLAY 0.680851 (-2190 9210);
PAINT MONO (-2190 9210);
FORCEPROP 0 LASTPIN (-2200 9250) $PN CF63
J 0
(-2190 9260);
DISPLAY 0.680851 (-2190 9260);
PAINT MONO (-2190 9260);
FORCEPROP 0 LASTPIN (-2200 9350) $PN CF65
J 0
(-2190 9360);
DISPLAY 0.680851 (-2190 9360);
PAINT MONO (-2190 9360);
FORCEPROP 0 LASTPIN (-2200 9400) $PN CH63
J 0
(-2190 9410);
DISPLAY 0.680851 (-2190 9410);
PAINT MONO (-2190 9410);
FORCEPROP 0 LASTPIN (-4600 10400) $PN CH71
J 2
(-4610 10410);
DISPLAY 0.680851 (-4610 10410);
PAINT MONO (-4610 10410);
FORCEPROP 0 LASTPIN (-4600 10150) $PN CJ21
J 2
(-4610 10160);
DISPLAY 0.680851 (-4610 10160);
PAINT MONO (-4610 10160);
FORCEPROP 0 LASTPIN (-2200 9000) $PN CJ23
J 0
(-2190 9010);
DISPLAY 0.680851 (-2190 9010);
PAINT MONO (-2190 9010);
FORCEPROP 0 LASTPIN (-2200 8950) $PN CJ25
J 0
(-2190 8960);
DISPLAY 0.680851 (-2190 8960);
PAINT MONO (-2190 8960);
FORCEPROP 0 LASTPIN (-2200 9300) $PN CJ66
J 0
(-2190 9310);
DISPLAY 0.680851 (-2190 9310);
PAINT MONO (-2190 9310);
FORCEPROP 0 LASTPIN (-2200 10400) $PN CK22
J 0
(-2190 10410);
DISPLAY 0.680851 (-2190 10410);
PAINT MONO (-2190 10410);
FORCEPROP 0 LASTPIN (-4600 10200) $PN CK24
J 2
(-4610 10210);
DISPLAY 0.680851 (-4610 10210);
PAINT MONO (-4610 10210);
FORCEPROP 0 LASTPIN (-2200 9050) $PN CL23
J 0
(-2190 9060);
DISPLAY 0.680851 (-2190 9060);
PAINT MONO (-2190 9060);
FORCEPROP 0 LASTPIN (-2200 8450) $PN CL66
J 0
(-2190 8460);
DISPLAY 0.680851 (-2190 8460);
PAINT MONO (-2190 8460);
FORCEPROP 0 LASTPIN (-4600 10300) $PN CN21
J 2
(-4610 10310);
DISPLAY 0.680851 (-4610 10310);
PAINT MONO (-4610 10310);
FORCEPROP 0 LASTPIN (-4600 9650) $PN CN23
J 2
(-4610 9660);
DISPLAY 0.680851 (-4610 9660);
PAINT MONO (-4610 9660);
FORCEPROP 0 LASTPIN (-4600 9900) $PN CP22
J 2
(-4610 9910);
DISPLAY 0.680851 (-4610 9910);
PAINT MONO (-4610 9910);
FORCEPROP 0 LASTPIN (-4600 9700) $PN CP24
J 2
(-4610 9710);
DISPLAY 0.680851 (-4610 9710);
PAINT MONO (-4610 9710);
FORCEPROP 0 LASTPIN (-4600 10250) $PN CR21
J 2
(-4610 10260);
DISPLAY 0.680851 (-4610 10260);
PAINT MONO (-4610 10260);
FORCEPROP 0 LASTPIN (-4600 10050) $PN CT22
J 2
(-4610 10060);
DISPLAY 0.680851 (-4610 10060);
PAINT MONO (-4610 10060);
FORCEPROP 0 LASTPIN (-4600 9750) $PN CT24
J 2
(-4610 9760);
DISPLAY 0.680851 (-4610 9760);
PAINT MONO (-4610 9760);
FORCEPROP 0 LASTPIN (-4600 9950) $PN CV22
J 2
(-4610 9960);
DISPLAY 0.680851 (-4610 9960);
PAINT MONO (-4610 9960);
FORCEPROP 0 LASTPIN (-4600 7900) $PN CV69
J 2
(-4610 7910);
DISPLAY 0.680851 (-4610 7910);
PAINT MONO (-4610 7910);
FORCEPROP 0 LASTPIN (-4600 7850) $PN CV71
J 2
(-4610 7860);
DISPLAY 0.680851 (-4610 7860);
PAINT MONO (-4610 7860);
FORCEPROP 0 LASTPIN (-4600 10350) $PN CW21
J 2
(-4610 10360);
DISPLAY 0.680851 (-4610 10360);
PAINT MONO (-4610 10360);
FORCEPROP 0 LASTPIN (-4600 7950) $PN CY69
J 2
(-4610 7960);
DISPLAY 0.680851 (-4610 7960);
PAINT MONO (-4610 7960);
FORCEPROP 0 LASTPIN (-4600 7800) $PN CY71
J 2
(-4610 7810);
DISPLAY 0.680851 (-4610 7810);
PAINT MONO (-4610 7810);
FORCEPROP 0 LASTPIN (-2200 8600) $PN CJ64
J 0
(-2190 8610);
DISPLAY 0.680851 (-2190 8610);
PAINT MONO (-2190 8610);
FORCEPROP 0 LASTPIN (-2200 8550) $PN CK65
J 0
(-2190 8560);
DISPLAY 0.680851 (-2190 8560);
PAINT MONO (-2190 8560);
FORCEPROP 0 LASTPIN (-2200 8650) $PN CH65
J 0
(-2190 8660);
DISPLAY 0.680851 (-2190 8660);
PAINT MONO (-2190 8660);
FORCEPROP 0 LASTPIN (-4600 10000) $PN CY22
J 2
(-4610 10010);
DISPLAY 0.680851 (-4610 10010);
PAINT MONO (-4610 10010);
FORCEPROP 0 LASTPIN (-2200 10450) $PN CF61
J 0
(-2190 10460);
DISPLAY 0.680851 (-2190 10460);
PAINT MONO (-2190 10460);
FORCEPROP 0 LASTPIN (-2200 9600) $PN AV69
J 0
(-2190 9610);
DISPLAY 0.680851 (-2190 9610);
PAINT MONO (-2190 9610);
FORCEPROP 0 LASTPIN (-2200 9550) $PN AY69
J 0
(-2190 9560);
DISPLAY 0.680851 (-2190 9560);
PAINT MONO (-2190 9560);
FORCEPROP 2 LAST CDS_LIB pure_quanta
J 0
(-3400 9125);
DISPLAY INVISIBLE (-3400 9125);
FORCEPROP 1 LAST NEEDS_NO_SIZE TRUE
J 0
(-3400 9125);
DISPLAY 0.723404 (-3400 9125);
PAINT GREEN (-3400 9125);
DISPLAY INVISIBLE (-3400 9125);
FORCEPROP 1 LAST CDS_LMAN_SYM_OUTLINE -1050,1500,1050,-1450
J 0
(-3400 9125);
DISPLAY 0.468085 (-3400 9125);
PAINT GREEN (-3400 9125);
DISPLAY INVISIBLE (-3400 9125);
FORCEPROP 2 LAST CDS_LOCATION U1
J 0
(-4450 10950);
DISPLAY 1.021277 (-4450 10950);
DISPLAY INVISIBLE (-4450 10950);
FORCEPROP 0 LAST $SEC 3
J 0
(-4450 10950);
DISPLAY 0.680851 (-4450 10950);
PAINT MONO (-4450 10950);
DISPLAY INVISIBLE (-4450 10950);
FORCEPROP 2 LAST CDS_SEC 3
J 0
(-4450 10950);
DISPLAY 1.021277 (-4450 10950);
DISPLAY INVISIBLE (-4450 10950);
FORCEPROP 1 LAST PATH I5
J 0
(-3400 9125);
DISPLAY 0.723404 (-3400 9125);
PAINT GREEN (-3400 9125);
DISPLAY INVISIBLE (-3400 9125);
FORCEADD QUANTA_TITLE_BLOCK_C..1
(1400 5000);
FORCEPROP 0 LAST CDS_CON_LAST_MODIFIED Fri Aug 25 14:00:29 2023
J 0
(-485 5015);
PAINT MONO (-485 5015);
DISPLAY INVISIBLE (-485 5015);
FORCEPROP 2 LAST CUSTOM_TXT_CDS <XR_PAGE_TITLE>
J 0
(-6490 10250);
DISPLAY 0.638298 (-6490 10250);
PAINT PINK (-6490 10250);
DISPLAY INVISIBLE (-6490 10250);
FORCEPROP 2 LAST CUSTOM_TXT_CDS <Q_NUMBER>
J 0
(-3 5103);
DISPLAY 1.212766 (-3 5103);
FORCEPROP 2 LAST CUSTOM_TXT_CDS <Q_PROJ>
J 0
(-982 5102);
DISPLAY 1.212766 (-982 5102);
FORCEPROP 2 LAST CUSTOM_TXT_CDS <Q_REV>
J 0
(1216 5103);
DISPLAY 1.212766 (1216 5103);
FORCEPROP 2 LAST CUSTOM_TXT_CDS <CON_PAGE_NUM> OF <CON_TOTAL_PAGES>
J 0
(954 5018);
DISPLAY 0.978723 (954 5018);
FORCEPROP 2 LAST CUSTOM_TXT_CDS <CON_LAST_MODIFIED>
J 0
(-485 5015);
DISPLAY 0.978723 (-485 5015);
FORCEPROP 1 LAST CUSTOM_TXT_CDS <NAME_2>
J 0
(-1775 5050);
FORCEPROP 1 LAST CUSTOM_TXT_CDS <NAME_1>
J 0
(-1775 5175);
FORCEPROP 1 LAST Q_TITLE SPR CPU1 MISC:(3 OF 30)
J 0
(-7966 5026);
DISPLAY 1.957447 (-7966 5026);
PAINT GREEN (-7966 5026);
FORCEPROP 1 LAST Q_DEPT 
J 1
(-2363 5049);
DISPLAY 1.957447 (-2363 5049);
PAINT GREEN (-2363 5049);
FORCEPROP 2 LAST CDS_LIB pure_quanta
J 0
(1400 5000);
PAINT MONO (1400 5000);
DISPLAY INVISIBLE (1400 5000);
FORCEPROP 1 LAST CDS_LMAN_SYM_OUTLINE -9475,6775,100,-125
J 0
(1400 5000);
DISPLAY 0.468085 (1400 5000);
PAINT GREEN (1400 5000);
DISPLAY INVISIBLE (1400 5000);
FORCEPROP 2 LAST PAGE_BORDER TRUE
J 0
(-6490 10250);
DISPLAY 0.638298 (-6490 10250);
PAINT PINK (-6490 10250);
DISPLAY INVISIBLE (-6490 10250);
FORCEPROP 2 LAST CDS_XR_PAGE_TITLE CR-46 : @S9S_MB_2U_LIB.S9S_MB_2U(SCH_1):PAGE46
J 0
(-6490 10250);
DISPLAY 0.638298 (-6490 10250);
PAINT PINK (-6490 10250);
DISPLAY INVISIBLE (-6490 10250);
FORCEPROP 1 LAST COMMENT_BODY TRUE
J 0
(1412 4987);
DISPLAY 0.978723 (1412 4987);
PAINT GREEN (1412 4987);
DISPLAY INVISIBLE (1412 4987);
WIRE 16 -1 (-6275 9750)(-4600 9750);
FORCEPROP 2 LAST SIG_NAME NC_FM_IBL_ADR_TRIGGER_CPU1_R
J 0
(-6212 9759);
DISPLAY 0.680851 (-6212 9759);
PAINT WHITE (-6212 9759);
WIRE 16 -1 (-6275 9700)(-4600 9700);
FORCEPROP 2 LAST SIG_NAME NC_FM_IBL_ADR_COMPLETE_CPU1_R
J 0
(-6212 9709);
DISPLAY 0.680851 (-6212 9709);
PAINT WHITE (-6212 9709);
WIRE 16 -1 (-4600 9650)(-6275 9650);
FORCEPROP 2 LAST SIG_NAME NC_FM_IBL_ADR_ACK_CPU1
J 0
(-6212 9659);
DISPLAY 0.680851 (-6212 9659);
PAINT WHITE (-6212 9659);
WIRE 16 -1 (-4600 10450)(-6275 10450);
FORCEPROP 2 LAST SIG_NAME PWRGD_PLT_AUX_CPU1_LVT3
J 0
(-6212 10459);
DISPLAY 0.680851 (-6212 10459);
PAINT WHITE (-6212 10459);
WIRE 16 -1 (-525 10400)(-2200 10400);
FORCEPROP 2 LAST SIG_NAME TP_FM_SYS_RST_CPU1_N
J 0
(-1941 10409);
DISPLAY 0.680851 (-1941 10409);
PAINT WHITE (-1941 10409);
WIRE 16 -1 (-4600 10200)(-6275 10200);
FORCEPROP 2 LAST SIG_NAME TP_FM_IBL_PWRBTN_CPU1_N
J 0
(-6212 10209);
DISPLAY 0.680851 (-6212 10209);
PAINT WHITE (-6212 10209);
WIRE 16 -1 (-525 9050)(-2200 9050);
FORCEPROP 2 LAST SIG_NAME TP_I2C_S3M_RTC_CPU1_SCL
J 0
(-1941 9059);
DISPLAY 0.680851 (-1941 9059);
PAINT WHITE (-1941 9059);
WIRE 16 -1 (-4600 9500)(-6275 9500);
FORCEPROP 2 LAST SIG_NAME NC_SPI_CPU1_NCM_CLK
J 0
(-6212 9509);
DISPLAY 0.680851 (-6212 9509);
PAINT WHITE (-6212 9509);
WIRE 16 -1 (-525 8450)(-2200 8450);
FORCEPROP 2 LAST SIG_NAME TP_CPU1_SSC_SYNC
J 0
(-1941 8459);
DISPLAY 0.680851 (-1941 8459);
PAINT WHITE (-1941 8459);
WIRE 16 -1 (-4600 10300)(-6275 10300);
FORCEPROP 2 LAST SIG_NAME TP_FM_IBL_SLPS4_CPU1_R_N
J 0
(-6212 10309);
DISPLAY 0.680851 (-6212 10309);
PAINT WHITE (-6212 10309);
WIRE 16 -1 (-4600 8350)(-6275 8350);
FORCEPROP 2 LAST SIG_NAME NC_ESPI_IBL_CPU1_IO2
J 0
(-6212 8359);
DISPLAY 0.680851 (-6212 8359);
PAINT WHITE (-6212 8359);
WIRE 16 -1 (-6275 9900)(-4600 9900);
FORCEPROP 2 LAST SIG_NAME TP_JTAG_CPU1_PLD_TDO_R
J 0
(-6212 9909);
DISPLAY 0.680851 (-6212 9909);
PAINT WHITE (-6212 9909);
WIRE 16 -1 (-4600 10250)(-6275 10250);
FORCEPROP 2 LAST SIG_NAME TP_FM_IBL_SLPS3_CPU1_R_N
J 0
(-6212 10259);
DISPLAY 0.680851 (-6212 10259);
PAINT WHITE (-6212 10259);
WIRE 16 -1 (-6275 10050)(-4600 10050);
FORCEPROP 2 LAST SIG_NAME TP_JTAG_CPU1_PLD_TDI
J 0
(-6212 10059);
DISPLAY 0.680851 (-6212 10059);
PAINT WHITE (-6212 10059);
WIRE 16 -1 (-4600 9950)(-6275 9950);
FORCEPROP 2 LAST SIG_NAME TP_JTAG_CPU1_PLD_TMS
J 0
(-6212 9959);
DISPLAY 0.680851 (-6212 9959);
PAINT WHITE (-6212 9959);
WIRE 16 -1 (-4600 7900)(-6275 7900);
FORCEPROP 2 LAST SIG_NAME NC_UART_IBL_CPU1_TXD
J 0
(-6212 7909);
DISPLAY 0.680851 (-6212 7909);
PAINT WHITE (-6212 7909);
WIRE 16 -1 (-4600 7850)(-6275 7850);
FORCEPROP 2 LAST SIG_NAME NC_UART_IBL_CPU1_CTS
J 0
(-6212 7859);
DISPLAY 0.680851 (-6212 7859);
PAINT WHITE (-6212 7859);
WIRE 16 -1 (-4600 10350)(-6275 10350);
FORCEPROP 2 LAST SIG_NAME TP_FM_IBL_SLPS5_CPU1_R_N
J 0
(-6212 10359);
DISPLAY 0.680851 (-6212 10359);
PAINT WHITE (-6212 10359);
WIRE 16 -1 (-525 8700)(-2200 8700);
FORCEPROP 2 LAST SIG_NAME FM_S3M_CPU1_CPLD_CRC_ERROR
J 0
(-1941 8709);
DISPLAY 0.680851 (-1941 8709);
PAINT WHITE (-1941 8709);
WIRE 16 -1 (-6275 10000)(-4600 10000);
FORCEPROP 2 LAST SIG_NAME PD_JTAG_CPU1_PLD_TCK
J 0
(-6212 10009);
DISPLAY 0.680851 (-6212 10009);
PAINT WHITE (-6212 10009);
WIRE 16 -1 (-4600 7950)(-6275 7950);
FORCEPROP 2 LAST SIG_NAME NC_UART_IBL_CPU1_RXD
J 0
(-6212 7959);
DISPLAY 0.680851 (-6212 7959);
PAINT WHITE (-6212 7959);
WIRE 16 -1 (-4600 7800)(-6275 7800);
FORCEPROP 2 LAST SIG_NAME NC_UART_IBL_CPU1_RTS
J 0
(-6212 7809);
DISPLAY 0.680851 (-6212 7809);
PAINT WHITE (-6212 7809);
WIRE 16 -1 (-4600 9050)(-6275 9050);
FORCEPROP 2 LAST SIG_NAME NC_SPI_S3M_CPU1_CS1_LVC1_R_N
J 0
(-6212 9059);
DISPLAY 0.680851 (-6212 9059);
PAINT WHITE (-6212 9059);
WIRE 16 -1 (-525 10350)(-2200 10350);
FORCEPROP 2 LAST SIG_NAME TP_FM_WAKE_CPU1_N
J 0
(-1941 10359);
DISPLAY 0.680851 (-1941 10359);
PAINT WHITE (-1941 10359);
WIRE 16 -1 (-6275 8950)(-4600 8950);
FORCEPROP 2 LAST SIG_NAME NC_SPI_S3M_CPU1_IO1_LVC1_R
J 0
(-6212 8959);
DISPLAY 0.680851 (-6212 8959);
PAINT WHITE (-6212 8959);
WIRE 16 -1 (-4600 9350)(-6275 9350);
FORCEPROP 2 LAST SIG_NAME NC_SPI_CPU1_NCM_IO1
J 0
(-6212 9359);
DISPLAY 0.680851 (-6212 9359);
PAINT WHITE (-6212 9359);
WIRE 16 -1 (-6275 9450)(-4600 9450);
FORCEPROP 2 LAST SIG_NAME NC_SPI_CPU1_NCM_CS0_N
J 0
(-6212 9459);
DISPLAY 0.680851 (-6212 9459);
PAINT WHITE (-6212 9459);
WIRE 16 -1 (-6275 9000)(-4600 9000);
FORCEPROP 2 LAST SIG_NAME NC_SPI_S3M_CPU1_IO0_LVC1_R
J 0
(-6212 9009);
DISPLAY 0.680851 (-6212 9009);
PAINT WHITE (-6212 9009);
WIRE 16 -1 (-6275 9400)(-4600 9400);
FORCEPROP 2 LAST SIG_NAME NC_SPI_CPU1_NCM_IO0
J 0
(-6212 9409);
DISPLAY 0.680851 (-6212 9409);
PAINT WHITE (-6212 9409);
WIRE 16 -1 (-4600 9200)(-6275 9200);
FORCEPROP 2 LAST SIG_NAME NC_SPI_S3M_CPU1_OE_LVC1_R_N
J 0
(-6212 9209);
DISPLAY 0.680851 (-6212 9209);
PAINT WHITE (-6212 9209);
WIRE 16 -1 (-6275 9100)(-4600 9100);
FORCEPROP 2 LAST SIG_NAME NC_SPI_S3M_CPU1_CS0_LVC1_R_N
J 0
(-6212 9109);
DISPLAY 0.680851 (-6212 9109);
PAINT WHITE (-6212 9109);
WIRE 16 -1 (-6275 9550)(-4600 9550);
FORCEPROP 2 LAST SIG_NAME NC_SPI_CPU1_NCM_OE_N
J 0
(-6212 9559);
DISPLAY 0.680851 (-6212 9559);
PAINT WHITE (-6212 9559);
WIRE 16 -1 (-525 8800)(-2200 8800);
FORCEPROP 2 LAST SIG_NAME TP_I3C_MNG3_BMC_SW_SDA
J 0
(-1941 8809);
DISPLAY 0.680851 (-1941 8809);
PAINT WHITE (-1941 8809);
WIRE 16 -1 (-6275 9150)(-4600 9150);
FORCEPROP 2 LAST SIG_NAME NC_SPI_S3M_CPU1_CLK_LVC1_R
J 0
(-6212 9159);
DISPLAY 0.680851 (-6212 9159);
PAINT WHITE (-6212 9159);
WIRE 16 -1 (-6275 8850)(-4600 8850);
FORCEPROP 2 LAST SIG_NAME NC_SPI_S3M_CPU1_IO3_LVC1_R
J 0
(-6212 8859);
DISPLAY 0.680851 (-6212 8859);
PAINT WHITE (-6212 8859);
WIRE 16 -1 (-6275 8200)(-4600 8200);
FORCEPROP 2 LAST SIG_NAME NC_ESPI_IBL_CPU1_ALERT1_N
J 0
(-6212 8209);
DISPLAY 0.680851 (-6212 8209);
PAINT WHITE (-6212 8209);
WIRE 16 -1 (-4600 8900)(-6275 8900);
FORCEPROP 2 LAST SIG_NAME NC_SPI_S3M_CPU1_IO2_LVC1_R
J 0
(-6212 8909);
DISPLAY 0.680851 (-6212 8909);
PAINT WHITE (-6212 8909);
WIRE 16 -1 (-525 8850)(-2200 8850);
FORCEPROP 2 LAST SIG_NAME TP_I3C_MNG3_BMC_SW_SCL
J 0
(-1941 8859);
DISPLAY 0.680851 (-1941 8859);
PAINT WHITE (-1941 8859);
WIRE 16 -1 (-6275 8250)(-4600 8250);
FORCEPROP 2 LAST SIG_NAME NC_ESPI_IBL_CPU1_ALERT0_N
J 0
(-6212 8259);
DISPLAY 0.680851 (-6212 8259);
PAINT WHITE (-6212 8259);
WIRE 16 -1 (-6275 8550)(-4600 8550);
FORCEPROP 2 LAST SIG_NAME NC_ESPI_IBL_CPU1_CS0_N
J 0
(-6212 8559);
DISPLAY 0.680851 (-6212 8559);
PAINT WHITE (-6212 8559);
WIRE 16 -1 (-4600 8600)(-6275 8600);
FORCEPROP 2 LAST SIG_NAME NC_ESPI_IBL_CPU1_CLK
J 0
(-6212 8609);
DISPLAY 0.680851 (-6212 8609);
PAINT WHITE (-6212 8609);
WIRE 16 -1 (-6275 8700)(-4600 8700);
FORCEPROP 2 LAST SIG_NAME NC_ESPI_IBL_CPU1_RESET_N
J 0
(-6212 8709);
DISPLAY 0.680851 (-6212 8709);
PAINT WHITE (-6212 8709);
WIRE 16 -1 (-6275 8650)(-4600 8650);
FORCEPROP 2 LAST SIG_NAME NC_ESPI_IBL_CPU1_OE_N
J 0
(-6212 8659);
DISPLAY 0.680851 (-6212 8659);
PAINT WHITE (-6212 8659);
WIRE 16 -1 (-6275 8500)(-4600 8500);
FORCEPROP 2 LAST SIG_NAME NC_ESPI_IBL_CPU1_CS1_N
J 0
(-6212 8509);
DISPLAY 0.680851 (-6212 8509);
PAINT WHITE (-6212 8509);
WIRE 16 -1 (-6275 8400)(-4600 8400);
FORCEPROP 2 LAST SIG_NAME NC_ESPI_IBL_CPU1_IO1
J 0
(-6212 8409);
DISPLAY 0.680851 (-6212 8409);
PAINT WHITE (-6212 8409);
WIRE 16 -1 (-4600 8450)(-6275 8450);
FORCEPROP 2 LAST SIG_NAME NC_ESPI_IBL_CPU1_IO0
J 0
(-6212 8459);
DISPLAY 0.680851 (-6212 8459);
PAINT WHITE (-6212 8459);
WIRE 16 -1 (-6275 8300)(-4600 8300);
FORCEPROP 2 LAST SIG_NAME NC_ESPI_IBL_CPU1_IO3
J 0
(-6212 8309);
DISPLAY 0.680851 (-6212 8309);
PAINT WHITE (-6212 8309);
WIRE 16 -1 (-525 9200)(-2200 9200);
FORCEPROP 2 LAST SIG_NAME TP_SGPIO_S3M_CPU1_GSXRST_N
J 0
(-1941 9209);
DISPLAY 0.680851 (-1941 9209);
PAINT WHITE (-1941 9209);
WIRE 16 -1 (-525 10450)(-2200 10450);
FORCEPROP 2 LAST SIG_NAME PUD_PCH_BOOT_MODE_CPU1
J 0
(-1941 10459);
DISPLAY 0.680851 (-1941 10459);
PAINT WHITE (-1941 10459);
WIRE 16 -1 (-525 9250)(-2200 9250);
FORCEPROP 2 LAST SIG_NAME TP_SGPIO_S3M_CPU1_GSXCLK
J 0
(-1941 9259);
DISPLAY 0.680851 (-1941 9259);
PAINT WHITE (-1941 9259);
WIRE 16 -1 (-525 9350)(-2200 9350);
FORCEPROP 2 LAST SIG_NAME TP_SGPIO_S3M_CPU1_GSXDOUT
J 0
(-1941 9359);
DISPLAY 0.680851 (-1941 9359);
PAINT WHITE (-1941 9359);
WIRE 16 -1 (-525 9400)(-2200 9400);
FORCEPROP 2 LAST SIG_NAME TP_SGPIO_S3M_CPU1_GSXDIN
J 0
(-1941 9409);
DISPLAY 0.680851 (-1941 9409);
PAINT WHITE (-1941 9409);
WIRE 16 -1 (-4600 10400)(-6275 10400);
FORCEPROP 2 LAST SIG_NAME TP_PWRGD_S0_PWROK_CPU1_LVC1
J 0
(-6212 10409);
DISPLAY 0.680851 (-6212 10409);
PAINT WHITE (-6212 10409);
WIRE 16 -1 (-4600 10150)(-6275 10150);
FORCEPROP 2 LAST SIG_NAME TP_CPU1_IBL_GRST_WARN_CPU1_N
J 0
(-6212 10159);
DISPLAY 0.680851 (-6212 10159);
PAINT WHITE (-6212 10159);
WIRE 16 -1 (-525 9000)(-2200 9000);
FORCEPROP 2 LAST SIG_NAME TP_I2C_S3M_RTC_CPU1_SDA
J 0
(-1941 9009);
DISPLAY 0.680851 (-1941 9009);
PAINT WHITE (-1941 9009);
WIRE 16 -1 (-525 8950)(-2200 8950);
FORCEPROP 2 LAST SIG_NAME TP_I2C_S3M_RTC_CPU1_RST_N
J 0
(-1941 8959);
DISPLAY 0.680851 (-1941 8959);
PAINT WHITE (-1941 8959);
WIRE 16 -1 (-525 9300)(-2200 9300);
FORCEPROP 2 LAST SIG_NAME TP_SGPIO_S3M_CPU1_GSXDLOAD
J 0
(-1941 9309);
DISPLAY 0.680851 (-1941 9309);
PAINT WHITE (-1941 9309);
WIRE 16 -1 (-525 9500)(-2200 9500);
FORCEPROP 2 LAST SIG_NAME FM_S3M_CPU1_LVC1_GPIO_4
J 0
(-1941 9509);
DISPLAY 0.680851 (-1941 9509);
PAINT WHITE (-1941 9509);
WIRE 16 -1 (-525 9550)(-2200 9550);
FORCEPROP 2 LAST SIG_NAME FM_S3M_CPU1_LVC1_GPIO_3
J 0
(-1941 9559);
DISPLAY 0.680851 (-1941 9559);
PAINT WHITE (-1941 9559);
WIRE 16 -1 (-525 9600)(-2200 9600);
FORCEPROP 2 LAST SIG_NAME FM_S3M_CPU1_LVC1_GPIO_2
J 0
(-1941 9609);
DISPLAY 0.680851 (-1941 9609);
PAINT WHITE (-1941 9609);
WIRE 16 -1 (-525 9650)(-2200 9650);
FORCEPROP 2 LAST SIG_NAME FM_S3M_CPU1_LVC1_GPIO_1
J 0
(-1941 9659);
DISPLAY 0.680851 (-1941 9659);
PAINT WHITE (-1941 9659);
WIRE 16 -1 (-525 9700)(-2200 9700);
FORCEPROP 2 LAST SIG_NAME FM_S3M_CPU1_LVC1_GPIO_0
J 0
(-1941 9709);
DISPLAY 0.680851 (-1941 9709);
PAINT WHITE (-1941 9709);
WIRE 16 -1 (-4600 8100)(-6275 8100);
FORCEPROP 2 LAST SIG_NAME SMB_S3M_CPU1_SCL
J 0
(-6212 8109);
DISPLAY 0.680851 (-6212 8109);
PAINT WHITE (-6212 8109);
WIRE 16 -1 (-4600 8050)(-6275 8050);
FORCEPROP 2 LAST SIG_NAME SMB_S3M_CPU1_SDA
J 0
(-6212 8059);
DISPLAY 0.680851 (-6212 8059);
PAINT WHITE (-6212 8059);
WIRE 16 -1 (-525 8600)(-2200 8600);
FORCEPROP 2 LAST SIG_NAME PU_S3M_CPU1_CPLD_CONFD
J 0
(-1941 8609);
DISPLAY 0.680851 (-1941 8609);
PAINT WHITE (-1941 8609);
WIRE 16 -1 (-525 8550)(-2200 8550);
FORCEPROP 2 LAST SIG_NAME FM_S3M_CPU1_CPLD_CONFIG_N
J 0
(-1941 8559);
DISPLAY 0.680851 (-1941 8559);
PAINT WHITE (-1941 8559);
WIRE 16 -1 (-525 8650)(-2200 8650);
FORCEPROP 2 LAST SIG_NAME PU_S3M_CPU1_CPLD_STATUS
J 0
(-1941 8659);
DISPLAY 0.680851 (-1941 8659);
PAINT WHITE (-1941 8659);
FORCENOTE
CPU1 SPI FLASH
(-7025 9025) 0;
DISPLAY LEFT (-7025 9025);
DISPLAY 1.021277 (-7025 9025);
PAINT YELLOW (-7025 9025);
QUIT
